(kicad_pcb
	(version 20260206)
	(generator "pcbnew")
	(generator_version "10.0")
	(general
		(thickness 1.6)
		(legacy_teardrops no)
	)
	(paper "A4")
	(title_block
		(title "04192023_DAF0TMB3IC0_F0TG_MB_C_brd_V02_OCP.brd")
		(comment 1 "Grand Teton / footprints 2083-2089 of 8354")
	)
	(layers
		(0 "F.Cu" signal "TOP")
		(4 "In1.Cu" signal "GND")
		(6 "In2.Cu" signal "IN1")
		(8 "In3.Cu" signal "GND1")
		(10 "In4.Cu" signal "IN2")
		(12 "In5.Cu" signal "GND2")
		(14 "In6.Cu" signal "IN3")
		(16 "In7.Cu" signal "GND3")
		(18 "In8.Cu" signal "VCC")
		(20 "In9.Cu" signal "VCC1")
		(22 "In10.Cu" signal "GND4")
		(24 "In11.Cu" signal "IN4")
		(26 "In12.Cu" signal "GND5")
		(28 "In13.Cu" signal "IN5")
		(30 "In14.Cu" signal "GND6")
		(32 "In15.Cu" signal "IN6")
		(34 "In16.Cu" signal "GND7")
		(2 "B.Cu" signal "BOTTOM")
		(9 "F.Adhes" user "F.Adhesive")
		(11 "B.Adhes" user "B.Adhesive")
		(13 "F.Paste" user "Package Geometry/Pastemask Top")
		(15 "B.Paste" user "Package Geometry/Pastemask Bottom")
		(5 "F.SilkS" user "Ref Des/Silkscreen Top")
		(7 "B.SilkS" user "Ref Des/Silkscreen Bottom")
		(1 "F.Mask" user "Board Geometry/Soldermask Top")
		(3 "B.Mask" user "Board Geometry/Soldermask Bottom")
		(17 "Dwgs.User" user "User.Drawings")
		(19 "Cmts.User" user "User.Comments")
		(21 "Eco1.User" user "User.Eco1")
		(23 "Eco2.User" user "User.Eco2")
		(25 "Edge.Cuts" user "Board Geometry/Outline")
		(27 "Margin" user)
		(31 "F.CrtYd" user "Package Geometry/Place Bound Top")
		(29 "B.CrtYd" user "Package Geometry/Place Bound Bottom")
		(35 "F.Fab" user "Ref Des/Assembly Top")
		(33 "B.Fab" user "Ref Des/Assembly Bottom")
	)
	(footprint ""
		(layer "F.Cu")
		(at 194.2211 -399.982182 180)
		(property "Reference" "PR3914"
			(at 0 0 180)
			(layer "F.SilkS")
			(hide yes)
			(effects
				(font
					(size 1.27 1.27)
				)
			)
		)
		(property "Value" ""
			(at 0 0 180)
			(layer "F.Fab")
			(effects
				(font
					(size 1.27 1.27)
				)
			)
		)
		(duplicate_pad_numbers_are_jumpers no)
		(fp_line
			(start 0.7874 0.4064)
			(end -0.7874 0.4064)
			(stroke
				(width 0.1524)
				(type default)
			)
			(layer "F.SilkS")
		)
		(fp_line
			(start 0.7874 -0.4064)
			(end 0.7874 0.4064)
			(stroke
				(width 0.1524)
				(type default)
			)
			(layer "F.SilkS")
		)
		(fp_line
			(start -0.7874 0.4064)
			(end -0.7874 -0.4064)
			(stroke
				(width 0.1524)
				(type default)
			)
			(layer "F.SilkS")
		)
		(fp_line
			(start -0.7874 -0.4064)
			(end 0.7874 -0.4064)
			(stroke
				(width 0.1524)
				(type default)
			)
			(layer "F.SilkS")
		)
		(fp_line
			(start 0.67945 0.3048)
			(end 0.120396 0.3048)
			(stroke
				(width 0.1)
				(type default)
			)
			(layer "F.Fab")
		)
		(fp_line
			(start 0.67945 -0.3048)
			(end 0.67945 0.3048)
			(stroke
				(width 0.1)
				(type default)
			)
			(layer "F.Fab")
		)
		(fp_line
			(start 0.12065 -0.2794)
			(end 0.12065 -0.3048)
			(stroke
				(width 0.1)
				(type default)
			)
			(layer "F.Fab")
		)
		(fp_line
			(start 0.12065 -0.3048)
			(end 0.67945 -0.3048)
			(stroke
				(width 0.1)
				(type default)
			)
			(layer "F.Fab")
		)
		(fp_line
			(start 0.120396 0.3048)
			(end 0.120396 0.2794)
			(stroke
				(width 0.1)
				(type default)
			)
			(layer "F.Fab")
		)
		(fp_line
			(start 0.120396 0.2794)
			(end -0.12065 0.2794)
			(stroke
				(width 0.1)
				(type default)
			)
			(layer "F.Fab")
		)
		(fp_line
			(start -0.12065 0.3048)
			(end -0.67945 0.3048)
			(stroke
				(width 0.1)
				(type default)
			)
			(layer "F.Fab")
		)
		(fp_line
			(start -0.12065 0.2794)
			(end -0.12065 0.3048)
			(stroke
				(width 0.1)
				(type default)
			)
			(layer "F.Fab")
		)
		(fp_line
			(start -0.12065 -0.2794)
			(end 0.12065 -0.2794)
			(stroke
				(width 0.1)
				(type default)
			)
			(layer "F.Fab")
		)
		(fp_line
			(start -0.12065 -0.305054)
			(end -0.12065 -0.2794)
			(stroke
				(width 0.1)
				(type default)
			)
			(layer "F.Fab")
		)
		(fp_line
			(start -0.67945 0.3048)
			(end -0.67945 -0.305054)
			(stroke
				(width 0.1)
				(type default)
			)
			(layer "F.Fab")
		)
		(fp_line
			(start -0.67945 -0.305054)
			(end -0.12065 -0.305054)
			(stroke
				(width 0.1)
				(type default)
			)
			(layer "F.Fab")
		)
		(pad "1" smd circle
			(at -0.40005 0 180)
			(size 0 0)
			(layers "F.Cu" "F.Mask" "F.Paste")
			(net "HSC_CS_1")
		)
		(pad "2" smd circle
			(at 0.40005 0 180)
			(size 0 0)
			(layers "F.Cu" "F.Mask" "F.Paste")
			(net "AGND_HSC")
		)
	)
	(footprint ""
		(layer "F.Cu")
		(at 166.920672 -350.248474)
		(property "Reference" "PC8"
			(at 0 0 0)
			(layer "F.SilkS")
			(hide yes)
			(effects
				(font
					(size 1.27 1.27)
				)
			)
		)
		(property "Value" ""
			(at 0 0 0)
			(layer "F.Fab")
			(effects
				(font
					(size 1.27 1.27)
				)
			)
		)
		(duplicate_pad_numbers_are_jumpers no)
		(fp_line
			(start -0.7874 -0.4064)
			(end 0.7874 -0.4064)
			(stroke
				(width 0.1524)
				(type default)
			)
			(layer "F.SilkS")
		)
		(fp_line
			(start -0.7874 0.4064)
			(end -0.7874 -0.4064)
			(stroke
				(width 0.1524)
				(type default)
			)
			(layer "F.SilkS")
		)
		(fp_line
			(start 0.7874 -0.4064)
			(end 0.7874 0.4064)
			(stroke
				(width 0.1524)
				(type default)
			)
			(layer "F.SilkS")
		)
		(fp_line
			(start 0.7874 0.4064)
			(end -0.7874 0.4064)
			(stroke
				(width 0.1524)
				(type default)
			)
			(layer "F.SilkS")
		)
		(fp_line
			(start -0.67945 -0.305054)
			(end -0.12065 -0.305054)
			(stroke
				(width 0.1)
				(type default)
			)
			(layer "F.Fab")
		)
		(fp_line
			(start -0.67945 0.3048)
			(end -0.67945 -0.305054)
			(stroke
				(width 0.1)
				(type default)
			)
			(layer "F.Fab")
		)
		(fp_line
			(start -0.12065 -0.305054)
			(end -0.12065 -0.2794)
			(stroke
				(width 0.1)
				(type default)
			)
			(layer "F.Fab")
		)
		(fp_line
			(start -0.12065 -0.2794)
			(end 0.12065 -0.2794)
			(stroke
				(width 0.1)
				(type default)
			)
			(layer "F.Fab")
		)
		(fp_line
			(start -0.12065 0.2794)
			(end -0.12065 0.3048)
			(stroke
				(width 0.1)
				(type default)
			)
			(layer "F.Fab")
		)
		(fp_line
			(start -0.12065 0.3048)
			(end -0.67945 0.3048)
			(stroke
				(width 0.1)
				(type default)
			)
			(layer "F.Fab")
		)
		(fp_line
			(start 0.120396 0.2794)
			(end -0.12065 0.2794)
			(stroke
				(width 0.1)
				(type default)
			)
			(layer "F.Fab")
		)
		(fp_line
			(start 0.120396 0.3048)
			(end 0.120396 0.2794)
			(stroke
				(width 0.1)
				(type default)
			)
			(layer "F.Fab")
		)
		(fp_line
			(start 0.12065 -0.3048)
			(end 0.67945 -0.3048)
			(stroke
				(width 0.1)
				(type default)
			)
			(layer "F.Fab")
		)
		(fp_line
			(start 0.12065 -0.2794)
			(end 0.12065 -0.3048)
			(stroke
				(width 0.1)
				(type default)
			)
			(layer "F.Fab")
		)
		(fp_line
			(start 0.67945 -0.3048)
			(end 0.67945 0.3048)
			(stroke
				(width 0.1)
				(type default)
			)
			(layer "F.Fab")
		)
		(fp_line
			(start 0.67945 0.3048)
			(end 0.120396 0.3048)
			(stroke
				(width 0.1)
				(type default)
			)
			(layer "F.Fab")
		)
		(pad "1" smd circle
			(at -0.40005 0)
			(size 0 0)
			(layers "F.Cu" "F.Mask" "F.Paste")
			(net "PVDD11_S3_P1_VINSEN")
		)
		(pad "2" smd circle
			(at 0.40005 0)
			(size 0 0)
			(layers "F.Cu" "F.Mask" "F.Paste")
			(net "GND")
		)
	)
	(footprint ""
		(layer "F.Cu")
		(at 359.417112 -261.747762 -90)
		(property "Reference" "C2158"
			(at 0 0 270)
			(layer "F.SilkS")
			(hide yes)
			(effects
				(font
					(size 1.27 1.27)
				)
			)
		)
		(property "Value" ""
			(at 0 0 270)
			(layer "F.Fab")
			(effects
				(font
					(size 1.27 1.27)
				)
			)
		)
		(duplicate_pad_numbers_are_jumpers no)
		(fp_line
			(start -0.7874 0.4064)
			(end -0.7874 -0.4064)
			(stroke
				(width 0.1524)
				(type default)
			)
			(layer "F.SilkS")
		)
		(fp_line
			(start 0.7874 0.4064)
			(end -0.7874 0.4064)
			(stroke
				(width 0.1524)
				(type default)
			)
			(layer "F.SilkS")
		)
		(fp_line
			(start -0.7874 -0.4064)
			(end 0.7874 -0.4064)
			(stroke
				(width 0.1524)
				(type default)
			)
			(layer "F.SilkS")
		)
		(fp_line
			(start 0.7874 -0.4064)
			(end 0.7874 0.4064)
			(stroke
				(width 0.1524)
				(type default)
			)
			(layer "F.SilkS")
		)
		(fp_line
			(start -0.67945 0.3048)
			(end -0.67945 -0.305054)
			(stroke
				(width 0.1)
				(type default)
			)
			(layer "F.Fab")
		)
		(fp_line
			(start -0.12065 0.3048)
			(end -0.67945 0.3048)
			(stroke
				(width 0.1)
				(type default)
			)
			(layer "F.Fab")
		)
		(fp_line
			(start 0.120396 0.3048)
			(end 0.120396 0.2794)
			(stroke
				(width 0.1)
				(type default)
			)
			(layer "F.Fab")
		)
		(fp_line
			(start 0.67945 0.3048)
			(end 0.120396 0.3048)
			(stroke
				(width 0.1)
				(type default)
			)
			(layer "F.Fab")
		)
		(fp_line
			(start -0.12065 0.2794)
			(end -0.12065 0.3048)
			(stroke
				(width 0.1)
				(type default)
			)
			(layer "F.Fab")
		)
		(fp_line
			(start 0.120396 0.2794)
			(end -0.12065 0.2794)
			(stroke
				(width 0.1)
				(type default)
			)
			(layer "F.Fab")
		)
		(fp_line
			(start -0.12065 -0.2794)
			(end 0.12065 -0.2794)
			(stroke
				(width 0.1)
				(type default)
			)
			(layer "F.Fab")
		)
		(fp_line
			(start 0.12065 -0.2794)
			(end 0.12065 -0.3048)
			(stroke
				(width 0.1)
				(type default)
			)
			(layer "F.Fab")
		)
		(fp_line
			(start 0.12065 -0.3048)
			(end 0.67945 -0.3048)
			(stroke
				(width 0.1)
				(type default)
			)
			(layer "F.Fab")
		)
		(fp_line
			(start 0.67945 -0.3048)
			(end 0.67945 0.3048)
			(stroke
				(width 0.1)
				(type default)
			)
			(layer "F.Fab")
		)
		(fp_line
			(start -0.67945 -0.305054)
			(end -0.12065 -0.305054)
			(stroke
				(width 0.1)
				(type default)
			)
			(layer "F.Fab")
		)
		(fp_line
			(start -0.12065 -0.305054)
			(end -0.12065 -0.2794)
			(stroke
				(width 0.1)
				(type default)
			)
			(layer "F.Fab")
		)
		(pad "1" smd circle
			(at -0.40005 0 270)
			(size 0 0)
			(layers "F.Cu" "F.Mask" "F.Paste")
			(net "PVDD11_S3_P0")
		)
		(pad "2" smd circle
			(at 0.40005 0 270)
			(size 0 0)
			(layers "F.Cu" "F.Mask" "F.Paste")
			(net "GND")
		)
	)
	(footprint ""
		(layer "F.Cu")
		(at 376.369072 -185.748168)
		(property "Reference" "PC179"
			(at 0 0 0)
			(layer "F.SilkS")
			(hide yes)
			(effects
				(font
					(size 1.27 1.27)
				)
			)
		)
		(property "Value" ""
			(at 0 0 0)
			(layer "F.Fab")
			(effects
				(font
					(size 1.27 1.27)
				)
			)
		)
		(duplicate_pad_numbers_are_jumpers no)
		(fp_line
			(start -0.7874 -0.4064)
			(end 0.7874 -0.4064)
			(stroke
				(width 0.1524)
				(type default)
			)
			(layer "F.SilkS")
		)
		(fp_line
			(start -0.7874 0.4064)
			(end -0.7874 -0.4064)
			(stroke
				(width 0.1524)
				(type default)
			)
			(layer "F.SilkS")
		)
		(fp_line
			(start 0.7874 -0.4064)
			(end 0.7874 0.4064)
			(stroke
				(width 0.1524)
				(type default)
			)
			(layer "F.SilkS")
		)
		(fp_line
			(start 0.7874 0.4064)
			(end -0.7874 0.4064)
			(stroke
				(width 0.1524)
				(type default)
			)
			(layer "F.SilkS")
		)
		(fp_line
			(start -0.67945 -0.305054)
			(end -0.12065 -0.305054)
			(stroke
				(width 0.1)
				(type default)
			)
			(layer "F.Fab")
		)
		(fp_line
			(start -0.67945 0.3048)
			(end -0.67945 -0.305054)
			(stroke
				(width 0.1)
				(type default)
			)
			(layer "F.Fab")
		)
		(fp_line
			(start -0.12065 -0.305054)
			(end -0.12065 -0.2794)
			(stroke
				(width 0.1)
				(type default)
			)
			(layer "F.Fab")
		)
		(fp_line
			(start -0.12065 -0.2794)
			(end 0.12065 -0.2794)
			(stroke
				(width 0.1)
				(type default)
			)
			(layer "F.Fab")
		)
		(fp_line
			(start -0.12065 0.2794)
			(end -0.12065 0.3048)
			(stroke
				(width 0.1)
				(type default)
			)
			(layer "F.Fab")
		)
		(fp_line
			(start -0.12065 0.3048)
			(end -0.67945 0.3048)
			(stroke
				(width 0.1)
				(type default)
			)
			(layer "F.Fab")
		)
		(fp_line
			(start 0.120396 0.2794)
			(end -0.12065 0.2794)
			(stroke
				(width 0.1)
				(type default)
			)
			(layer "F.Fab")
		)
		(fp_line
			(start 0.120396 0.3048)
			(end 0.120396 0.2794)
			(stroke
				(width 0.1)
				(type default)
			)
			(layer "F.Fab")
		)
		(fp_line
			(start 0.12065 -0.3048)
			(end 0.67945 -0.3048)
			(stroke
				(width 0.1)
				(type default)
			)
			(layer "F.Fab")
		)
		(fp_line
			(start 0.12065 -0.2794)
			(end 0.12065 -0.3048)
			(stroke
				(width 0.1)
				(type default)
			)
			(layer "F.Fab")
		)
		(fp_line
			(start 0.67945 -0.3048)
			(end 0.67945 0.3048)
			(stroke
				(width 0.1)
				(type default)
			)
			(layer "F.Fab")
		)
		(fp_line
			(start 0.67945 0.3048)
			(end 0.120396 0.3048)
			(stroke
				(width 0.1)
				(type default)
			)
			(layer "F.Fab")
		)
		(pad "1" smd circle
			(at -0.40005 0)
			(size 0 0)
			(layers "F.Cu" "F.Mask" "F.Paste")
			(net "SW_PVDDCR_CPU0_P0_SW2")
		)
		(pad "2" smd circle
			(at 0.40005 0)
			(size 0 0)
			(layers "F.Cu" "F.Mask" "F.Paste")
			(net "SW_PVDDCR_CPU0_P0_SW2_RC")
		)
	)
	(footprint ""
		(layer "F.Cu")
		(at 70.739 -52.578)
		(property "Reference" "R1172"
			(at 0 0 0)
			(layer "F.SilkS")
			(hide yes)
			(effects
				(font
					(size 1.27 1.27)
				)
			)
		)
		(property "Value" ""
			(at 0 0 0)
			(layer "F.Fab")
			(effects
				(font
					(size 1.27 1.27)
				)
			)
		)
		(duplicate_pad_numbers_are_jumpers no)
		(fp_line
			(start -0.7874 -0.4064)
			(end 0.7874 -0.4064)
			(stroke
				(width 0.1524)
				(type default)
			)
			(layer "F.SilkS")
		)
		(fp_line
			(start -0.7874 0.4064)
			(end -0.7874 -0.4064)
			(stroke
				(width 0.1524)
				(type default)
			)
			(layer "F.SilkS")
		)
		(fp_line
			(start 0.7874 -0.4064)
			(end 0.7874 0.4064)
			(stroke
				(width 0.1524)
				(type default)
			)
			(layer "F.SilkS")
		)
		(fp_line
			(start 0.7874 0.4064)
			(end -0.7874 0.4064)
			(stroke
				(width 0.1524)
				(type default)
			)
			(layer "F.SilkS")
		)
		(fp_line
			(start -0.67945 -0.305054)
			(end -0.12065 -0.305054)
			(stroke
				(width 0.1)
				(type default)
			)
			(layer "F.Fab")
		)
		(fp_line
			(start -0.67945 0.3048)
			(end -0.67945 -0.305054)
			(stroke
				(width 0.1)
				(type default)
			)
			(layer "F.Fab")
		)
		(fp_line
			(start -0.12065 -0.305054)
			(end -0.12065 -0.2794)
			(stroke
				(width 0.1)
				(type default)
			)
			(layer "F.Fab")
		)
		(fp_line
			(start -0.12065 -0.2794)
			(end 0.12065 -0.2794)
			(stroke
				(width 0.1)
				(type default)
			)
			(layer "F.Fab")
		)
		(fp_line
			(start -0.12065 0.2794)
			(end -0.12065 0.3048)
			(stroke
				(width 0.1)
				(type default)
			)
			(layer "F.Fab")
		)
		(fp_line
			(start -0.12065 0.3048)
			(end -0.67945 0.3048)
			(stroke
				(width 0.1)
				(type default)
			)
			(layer "F.Fab")
		)
		(fp_line
			(start 0.120396 0.2794)
			(end -0.12065 0.2794)
			(stroke
				(width 0.1)
				(type default)
			)
			(layer "F.Fab")
		)
		(fp_line
			(start 0.120396 0.3048)
			(end 0.120396 0.2794)
			(stroke
				(width 0.1)
				(type default)
			)
			(layer "F.Fab")
		)
		(fp_line
			(start 0.12065 -0.3048)
			(end 0.67945 -0.3048)
			(stroke
				(width 0.1)
				(type default)
			)
			(layer "F.Fab")
		)
		(fp_line
			(start 0.12065 -0.2794)
			(end 0.12065 -0.3048)
			(stroke
				(width 0.1)
				(type default)
			)
			(layer "F.Fab")
		)
		(fp_line
			(start 0.67945 -0.3048)
			(end 0.67945 0.3048)
			(stroke
				(width 0.1)
				(type default)
			)
			(layer "F.Fab")
		)
		(fp_line
			(start 0.67945 0.3048)
			(end 0.120396 0.3048)
			(stroke
				(width 0.1)
				(type default)
			)
			(layer "F.Fab")
		)
		(pad "1" smd circle
			(at -0.40005 0)
			(size 0 0)
			(layers "F.Cu" "F.Mask" "F.Paste")
			(net "P3V3_AUX")
		)
		(pad "2" smd circle
			(at 0.40005 0)
			(size 0 0)
			(layers "F.Cu" "F.Mask" "F.Paste")
			(net "OCP_V3_2_AUX_PWR_EN")
		)
	)
	(footprint ""
		(layer "F.Cu")
		(at 322.364862 -403.21484 90)
		(property "Reference" "R6808"
			(at 0 0 90)
			(layer "F.SilkS")
			(hide yes)
			(effects
				(font
					(size 1.27 1.27)
				)
			)
		)
		(property "Value" ""
			(at 0 0 90)
			(layer "F.Fab")
			(effects
				(font
					(size 1.27 1.27)
				)
			)
		)
		(duplicate_pad_numbers_are_jumpers no)
		(fp_line
			(start 0.32512 -0.175006)
			(end 0.32512 0.175006)
			(stroke
				(width 0.1)
				(type default)
			)
			(layer "F.Fab")
		)
		(fp_line
			(start -0.32512 -0.175006)
			(end 0.32512 -0.175006)
			(stroke
				(width 0.1)
				(type default)
			)
			(layer "F.Fab")
		)
		(fp_line
			(start 0.32512 0.175006)
			(end -0.32512 0.175006)
			(stroke
				(width 0.1)
				(type default)
			)
			(layer "F.Fab")
		)
		(fp_line
			(start -0.32512 0.175006)
			(end -0.32512 -0.175006)
			(stroke
				(width 0.1)
				(type default)
			)
			(layer "F.Fab")
		)
		(pad "1" smd rect
			(at -0.2667 0 90)
			(size 0.3048 0.381)
			(layers "F.Cu" "F.Mask" "F.Paste")
			(net "P1V8_CPU0_RT_1D")
		)
		(pad "2" smd rect
			(at 0.2667 0 270)
			(size 0.3048 0.381)
			(layers "F.Cu" "F.Mask" "F.Paste")
			(net "RT_CPU0_P0_VQPS")
		)
	)
	(footprint ""
		(layer "F.Cu")
		(at 111.91494 -394.166852 -90)
		(property "Reference" "R908"
			(at 0 0 270)
			(layer "F.SilkS")
			(hide yes)
			(effects
				(font
					(size 1.27 1.27)
				)
			)
		)
		(property "Value" ""
			(at 0 0 270)
			(layer "F.Fab")
			(effects
				(font
					(size 1.27 1.27)
				)
			)
		)
		(duplicate_pad_numbers_are_jumpers no)
		(fp_line
			(start -0.32512 0.175006)
			(end -0.32512 -0.175006)
			(stroke
				(width 0.1)
				(type default)
			)
			(layer "F.Fab")
		)
		(fp_line
			(start 0.32512 0.175006)
			(end -0.32512 0.175006)
			(stroke
				(width 0.1)
				(type default)
			)
			(layer "F.Fab")
		)
		(fp_line
			(start -0.32512 -0.175006)
			(end 0.32512 -0.175006)
			(stroke
				(width 0.1)
				(type default)
			)
			(layer "F.Fab")
		)
		(fp_line
			(start 0.32512 -0.175006)
			(end 0.32512 0.175006)
			(stroke
				(width 0.1)
				(type default)
			)
			(layer "F.Fab")
		)
		(pad "1" smd rect
			(at -0.2667 0 270)
			(size 0.3048 0.381)
			(layers "F.Cu" "F.Mask" "F.Paste")
			(net "RST_RT_CPU1_P3_RESET_R_N")
		)
		(pad "2" smd rect
			(at 0.2667 0 90)
			(size 0.3048 0.381)
			(layers "F.Cu" "F.Mask" "F.Paste")
			(net "GND")
		)
	)
)
